# BASEBOARD_FAB2 (Tioga Pass) — schematic netlist excerpt (pin names and nets, part order shuffled) for the footprints in the layout excerpt that follows; sources: Cadence DE-HDL packaged netlist, KiCad conversion of Wiwynn_Tioga_Pass_MB.brd

C1M27  CAP  10UF 16V 10% X6S  pkg 0805  page 186 : A = P12V_STBY ; B = GND
R25W146  RES  4.75K 1% CHIP  pkg 0402  page 150 : A = GND ; B = RMII_BMC_OCP_TXEN
R9P5  RES  10.0K 1% CHIP  pkg 0402  page 200 : A = P3V3_STBY ; B = FM_DISABLE_FAN_N

(kicad_pcb
	(version 20260206)
	(generator "pcbnew")
	(generator_version "10.0")
	(general
		(thickness 1.6)
		(legacy_teardrops no)
	)
	(paper "A4")
	(title_block
		(title "Wiwynn_Tioga_Pass_MB.brd")
		(comment 1 "Tioga Pass / footprints 4760-4762 of 4770")
	)
	(layers
		(0 "F.Cu" signal "TOP")
		(4 "In1.Cu" signal "L2GND")
		(6 "In2.Cu" signal "L3")
		(8 "In3.Cu" signal "L4GND")
		(10 "In4.Cu" signal "L5")
		(12 "In5.Cu" signal "L6GND")
		(14 "In6.Cu" signal "L7VCC")
		(16 "In7.Cu" signal "L8VCC")
		(18 "In8.Cu" signal "L9GND")
		(20 "In9.Cu" signal "L10")
		(22 "In10.Cu" signal "L11GND")
		(24 "In11.Cu" signal "L12")
		(26 "In12.Cu" signal "L13GND")
		(2 "B.Cu" signal "BOTTOM")
		(9 "F.Adhes" user "F.Adhesive")
		(11 "B.Adhes" user "B.Adhesive")
		(13 "F.Paste" user "Package Geometry/Pastemask Top")
		(15 "B.Paste" user "Package Geometry/Pastemask Bottom")
		(5 "F.SilkS" user "Ref Des/Silkscreen Top")
		(7 "B.SilkS" user "Ref Des/Silkscreen Bottom")
		(1 "F.Mask" user "Board Geometry/Soldermask Top")
		(3 "B.Mask" user "Board Geometry/Soldermask Bottom")
		(17 "Dwgs.User" user "User.Drawings")
		(19 "Cmts.User" user "User.Comments")
		(21 "Eco1.User" user "User.Eco1")
		(23 "Eco2.User" user "User.Eco2")
		(25 "Edge.Cuts" user "Board Geometry/Outline")
		(27 "Margin" user)
		(31 "F.CrtYd" user "Package Geometry/Place Bound Top")
		(29 "B.CrtYd" user "Package Geometry/Place Bound Bottom")
		(35 "F.Fab" user "Ref Des/Assembly Top")
		(33 "B.Fab" user "Ref Des/Assembly Bottom")
	)
	(footprint ""
		(layer "B.Cu")
		(at 25.9842 -85.9028 90)
		(property "Reference" "R9P5"
			(at 0 0 90)
			(layer "B.SilkS")
			(hide yes)
			(effects
				(font
					(size 1.27 1.27)
				)
				(justify mirror)
			)
		)
		(property "Value" ""
			(at 0 0 90)
			(layer "B.Fab")
			(effects
				(font
					(size 1.27 1.27)
				)
				(justify mirror)
			)
		)
		(duplicate_pad_numbers_are_jumpers no)
		(fp_poly
			(pts
				(xy 0.2794 -0.1016) (xy -0.2794 -0.1016) (xy -0.2794 0.9906) (xy 0.2794 0.9906)
			)
			(stroke
				(width 0)
				(type default)
			)
			(fill no)
			(layer "B.CrtYd")
		)
		(fp_line
			(start 0.2794 -0.1016)
			(end 0.2794 0.9906)
			(stroke
				(width 0.1)
				(type default)
			)
			(layer "B.Fab")
		)
		(fp_line
			(start -0.2794 -0.1016)
			(end 0.2794 -0.1016)
			(stroke
				(width 0.1)
				(type default)
			)
			(layer "B.Fab")
		)
		(fp_line
			(start 0.2794 0.9906)
			(end -0.2794 0.9906)
			(stroke
				(width 0.1)
				(type default)
			)
			(layer "B.Fab")
		)
		(fp_line
			(start -0.2794 0.9906)
			(end -0.2794 -0.1016)
			(stroke
				(width 0.1)
				(type default)
			)
			(layer "B.Fab")
		)
		(pad "1" smd rect
			(at 0 0 270)
			(size 0.508 0.508)
			(layers "B.Cu" "B.Mask" "B.Paste")
			(net "P3V3_STBY")
		)
		(pad "2" smd rect
			(at 0 0.889 270)
			(size 0.508 0.508)
			(layers "B.Cu" "B.Mask" "B.Paste")
			(net "FM_DISABLE_FAN_N")
		)
		(zone
			(layer "B.Cu")
			(hatch none 0.5)
			(connect_pads
				(clearance 0)
			)
			(min_thickness 0.25)
			(keepout
				(tracks allowed)
				(vias not_allowed)
				(pads allowed)
				(copperpour not_allowed)
				(footprints allowed)
			)
			(placement
				(enabled no)
				(sheetname "")
			)
			(fill
				(thermal_gap 0.5)
				(thermal_bridge_width 0.5)
				(island_removal_mode 0)
			)
			(polygon
				(pts
					(xy 26.2382 -86.1568) (xy 26.2382 -85.6488) (xy 26.6192 -85.6488) (xy 26.6192 -86.1568)
				)
			)
		)
		(zone
			(layer "B.Cu")
			(hatch none 0.5)
			(connect_pads
				(clearance 0)
			)
			(min_thickness 0.25)
			(keepout
				(tracks not_allowed)
				(vias allowed)
				(pads allowed)
				(copperpour not_allowed)
				(footprints allowed)
			)
			(placement
				(enabled no)
				(sheetname "")
			)
			(fill
				(thermal_gap 0.5)
				(thermal_bridge_width 0.5)
				(island_removal_mode 0)
			)
			(polygon
				(pts
					(xy 26.6192 -86.1568) (xy 26.6192 -85.6488) (xy 26.2382 -85.6488) (xy 26.2382 -86.1568)
				)
			)
		)
	)
	(footprint ""
		(layer "B.Cu")
		(at 486.41 -111.94542 -90)
		(property "Reference" "C1M27"
			(at 0 0 90)
			(layer "B.SilkS")
			(hide yes)
			(effects
				(font
					(size 1.27 1.27)
				)
				(justify mirror)
			)
		)
		(property "Value" ""
			(at 0 0 90)
			(layer "B.Fab")
			(effects
				(font
					(size 1.27 1.27)
				)
				(justify mirror)
			)
		)
		(duplicate_pad_numbers_are_jumpers no)
		(fp_rect
			(start 0.7239 1.9939)
			(end -0.7239 -0.2159)
			(stroke
				(width 0)
				(type default)
			)
			(fill no)
			(layer "B.CrtYd")
		)
		(fp_line
			(start -0.7239 1.9939)
			(end -0.7239 -0.2159)
			(stroke
				(width 0.1)
				(type default)
			)
			(layer "B.Fab")
		)
		(fp_line
			(start 0.7239 1.9939)
			(end -0.7239 1.9939)
			(stroke
				(width 0.1)
				(type default)
			)
			(layer "B.Fab")
		)
		(fp_line
			(start -0.7239 -0.2159)
			(end 0.7239 -0.2159)
			(stroke
				(width 0.1)
				(type default)
			)
			(layer "B.Fab")
		)
		(fp_line
			(start 0.7239 -0.2159)
			(end 0.7239 1.9939)
			(stroke
				(width 0.1)
				(type default)
			)
			(layer "B.Fab")
		)
		(pad "1" smd rect
			(at 0 0 90)
			(size 1.27 1.016)
			(layers "B.Cu" "B.Mask" "B.Paste")
			(net "P12V_STBY")
		)
		(pad "2" smd rect
			(at 0 1.778 90)
			(size 1.27 1.016)
			(layers "B.Cu" "B.Mask" "B.Paste")
			(net "GND")
		)
		(zone
			(layer "B.Cu")
			(hatch none 0.5)
			(connect_pads
				(clearance 0)
			)
			(min_thickness 0.25)
			(keepout
				(tracks not_allowed)
				(vias allowed)
				(pads allowed)
				(copperpour not_allowed)
				(footprints allowed)
			)
			(placement
				(enabled no)
				(sheetname "")
			)
			(fill
				(thermal_gap 0.5)
				(thermal_bridge_width 0.5)
				(island_removal_mode 0)
			)
			(polygon
				(pts
					(xy 485.14 -111.31042) (xy 485.902 -111.31042) (xy 485.902 -112.58042) (xy 485.14 -112.58042)
				)
			)
		)
	)
	(footprint ""
		(layer "B.Cu")
		(at 405.9174 -33.4264 -90)
		(property "Reference" "R25W146"
			(at 0.8382 -0.67818 270)
			(unlocked yes)
			(layer "B.SilkS")
			(effects
				(font
					(size 0.4064 0.254)
					(thickness 0.1524)
				)
				(justify left mirror)
			)
		)
		(property "Value" ""
			(at 0 0 90)
			(layer "B.Fab")
			(effects
				(font
					(size 1.27 1.27)
				)
				(justify mirror)
			)
		)
		(duplicate_pad_numbers_are_jumpers no)
		(fp_poly
			(pts
				(xy 0.2794 -0.1016) (xy -0.2794 -0.1016) (xy -0.2794 0.9906) (xy 0.2794 0.9906)
			)
			(stroke
				(width 0)
				(type default)
			)
			(fill no)
			(layer "B.CrtYd")
		)
		(fp_line
			(start -0.2794 0.9906)
			(end -0.2794 -0.1016)
			(stroke
				(width 0.1)
				(type default)
			)
			(layer "B.Fab")
		)
		(fp_line
			(start 0.2794 0.9906)
			(end -0.2794 0.9906)
			(stroke
				(width 0.1)
				(type default)
			)
			(layer "B.Fab")
		)
		(fp_line
			(start -0.2794 -0.1016)
			(end 0.2794 -0.1016)
			(stroke
				(width 0.1)
				(type default)
			)
			(layer "B.Fab")
		)
		(fp_line
			(start 0.2794 -0.1016)
			(end 0.2794 0.9906)
			(stroke
				(width 0.1)
				(type default)
			)
			(layer "B.Fab")
		)
		(pad "1" smd rect
			(at 0 0 90)
			(size 0.508 0.508)
			(layers "B.Cu" "B.Mask" "B.Paste")
			(net "GND")
		)
		(pad "2" smd rect
			(at 0 0.889 90)
			(size 0.508 0.508)
			(layers "B.Cu" "B.Mask" "B.Paste")
			(net "RMII_BMC_OCP_TXEN")
		)
		(zone
			(layer "B.Cu")
			(hatch none 0.5)
			(connect_pads
				(clearance 0)
			)
			(min_thickness 0.25)
			(keepout
				(tracks not_allowed)
				(vias allowed)
				(pads allowed)
				(copperpour not_allowed)
				(footprints allowed)
			)
			(placement
				(enabled no)
				(sheetname "")
			)
			(fill
				(thermal_gap 0.5)
				(thermal_bridge_width 0.5)
				(island_removal_mode 0)
			)
			(polygon
				(pts
					(xy 405.2824 -33.1724) (xy 405.2824 -33.6804) (xy 405.6634 -33.6804) (xy 405.6634 -33.1724)
				)
			)
		)
		(zone
			(layer "B.Cu")
			(hatch none 0.5)
			(connect_pads
				(clearance 0)
			)
			(min_thickness 0.25)
			(keepout
				(tracks allowed)
				(vias not_allowed)
				(pads allowed)
				(copperpour not_allowed)
				(footprints allowed)
			)
			(placement
				(enabled no)
				(sheetname "")
			)
			(fill
				(thermal_gap 0.5)
				(thermal_bridge_width 0.5)
				(island_removal_mode 0)
			)
			(polygon
				(pts
					(xy 405.6634 -33.1724) (xy 405.6634 -33.6804) (xy 405.2824 -33.6804) (xy 405.2824 -33.1724)
				)
			)
		)
	)
)
